(kicad_pcb
	(version 20241229)
	(generator "pcbnew")
	(generator_version "9.0")
	(general
		(thickness 1.599998)
		(legacy_teardrops no)
	)
	(paper "A4")
	(title_block
		(date "2023-02-12")
		(rev "1.1.5")
		(comment 9 "footprints 89-94 of 473")
	)
	(layers
		(0 "F.Cu" signal)
		(4 "In1.Cu" power "In1.GND")
		(6 "In2.Cu" signal)
		(8 "In3.Cu" power "In3.GND")
		(10 "In4.Cu" power "In4.VCC")
		(12 "In5.Cu" signal)
		(14 "In6.Cu" power "In6.VCC")
		(2 "B.Cu" signal)
		(9 "F.Adhes" user "F.Adhesive")
		(11 "B.Adhes" user "B.Adhesive")
		(13 "F.Paste" user)
		(15 "B.Paste" user)
		(5 "F.SilkS" user "F.Silkscreen")
		(7 "B.SilkS" user "B.Silkscreen")
		(1 "F.Mask" user)
		(3 "B.Mask" user)
		(17 "Dwgs.User" user "User.Drawings")
		(19 "Cmts.User" user "User.Comments")
		(21 "Eco1.User" user "User.Eco1")
		(23 "Eco2.User" user "User.Eco2")
		(25 "Edge.Cuts" user)
		(27 "Margin" user)
		(31 "F.CrtYd" user "F.Courtyard")
		(29 "B.CrtYd" user "B.Courtyard")
		(35 "F.Fab" user)
		(33 "B.Fab" user)
	)
	(footprint "antmicro-footprints:TP_SMD_1mm"
		(layer "F.Cu")
		(at 150.3992 119.16 90)
		(property "Reference" "TP5"
			(at 0.36 0.0008 90)
			(layer "F.SilkS")
			(effects
				(font
					(size 0.7 0.7)
					(thickness 0.15)
				)
				(justify left bottom)
			)
		)
		(property "Value" "TP_1mm_SMD"
			(at 0 1.4 90)
			(layer "F.Fab")
			(effects
				(font
					(size 0.7 0.7)
					(thickness 0.15)
				)
				(justify left bottom)
			)
		)
		(property "Description" "Test Point 1mm"
			(at 0 0 90)
			(layer "F.Fab")
			(hide yes)
			(effects
				(font
					(size 1.27 1.27)
					(thickness 0.15)
				)
			)
		)
		(property "Author" "Antmicro"
			(at 269.5592 -31.2392 0)
			(layer "F.Fab")
			(hide yes)
			(effects
				(font
					(size 1 1)
					(thickness 0.15)
				)
			)
		)
		(property "License" "Apache-2.0"
			(at 269.5592 -31.2392 0)
			(layer "F.Fab")
			(hide yes)
			(effects
				(font
					(size 1 1)
					(thickness 0.15)
				)
			)
		)
		(property "MPN" ""
			(at 269.5592 -31.2392 0)
			(layer "F.Fab")
			(hide yes)
			(effects
				(font
					(size 1 1)
					(thickness 0.15)
				)
			)
		)
		(property "Manufacturer" ""
			(at 269.5592 -31.2392 0)
			(layer "F.Fab")
			(hide yes)
			(effects
				(font
					(size 1 1)
					(thickness 0.15)
				)
			)
		)
		(sheetname "Interfaces")
		(sheetfile "interfaces.kicad_sch")
		(attr exclude_from_pos_files)
		(pad "1" smd circle
			(at 0 0 90)
			(size 1 1)
			(layers "F.Cu" "F.Mask")
			(net 82 "Net-(J2-SDA)")
			(pinfunction "1")
			(pintype "passive")
		)
	)
	(footprint "antmicro-footprints:TP_SMD_1mm"
		(layer "F.Cu")
		(at 149.534 121.16 90)
		(property "Reference" "TP6"
			(at -2.24 -0.534 90)
			(layer "F.SilkS")
			(effects
				(font
					(size 0.7 0.7)
					(thickness 0.15)
				)
				(justify left bottom)
			)
		)
		(property "Value" "TP_1mm_SMD"
			(at 0 1.4 90)
			(layer "F.Fab")
			(effects
				(font
					(size 0.7 0.7)
					(thickness 0.15)
				)
				(justify left bottom)
			)
		)
		(property "Description" "Test Point 1mm"
			(at 0 0 90)
			(layer "F.Fab")
			(hide yes)
			(effects
				(font
					(size 1.27 1.27)
					(thickness 0.15)
				)
			)
		)
		(property "Author" "Antmicro"
			(at 270.694 -28.374 0)
			(layer "F.Fab")
			(hide yes)
			(effects
				(font
					(size 1 1)
					(thickness 0.15)
				)
			)
		)
		(property "License" "Apache-2.0"
			(at 270.694 -28.374 0)
			(layer "F.Fab")
			(hide yes)
			(effects
				(font
					(size 1 1)
					(thickness 0.15)
				)
			)
		)
		(property "MPN" ""
			(at 270.694 -28.374 0)
			(layer "F.Fab")
			(hide yes)
			(effects
				(font
					(size 1 1)
					(thickness 0.15)
				)
			)
		)
		(property "Manufacturer" ""
			(at 270.694 -28.374 0)
			(layer "F.Fab")
			(hide yes)
			(effects
				(font
					(size 1 1)
					(thickness 0.15)
				)
			)
		)
		(sheetname "Interfaces")
		(sheetfile "interfaces.kicad_sch")
		(attr exclude_from_pos_files)
		(pad "1" smd circle
			(at 0 0 90)
			(size 1 1)
			(layers "F.Cu" "F.Mask")
			(net 83 "Net-(J2-+5V)")
			(pinfunction "1")
			(pintype "passive")
		)
	)
	(footprint "antmicro-footprints:HDMI-A_Receptacle_WE_685119134923"
		(layer "F.Cu")
		(at 155.09 130.104 180)
		(property "Reference" "J2"
			(at -6.454 6.914 180)
			(layer "F.SilkS")
			(effects
				(font
					(size 0.7 0.7)
					(thickness 0.15)
				)
				(justify left bottom)
			)
		)
		(property "Value" "HDMI-A_685119134923"
			(at 0 7.8 180)
			(layer "F.Fab")
			(effects
				(font
					(size 0.7 0.7)
					(thickness 0.15)
				)
				(justify left bottom)
			)
		)
		(property "Description" "HDMI Receptacle Connector 19 Position Surface Mount, Right Angle; Through Hole"
			(at 0 0 180)
			(layer "F.Fab")
			(hide yes)
			(effects
				(font
					(size 1.27 1.27)
					(thickness 0.15)
				)
			)
		)
		(property "Author" "Antmicro"
			(at 310.18 260.208 0)
			(layer "F.Fab")
			(hide yes)
			(effects
				(font
					(size 1 1)
					(thickness 0.15)
				)
			)
		)
		(property "License" "Apache-2.0"
			(at 310.18 260.208 0)
			(layer "F.Fab")
			(hide yes)
			(effects
				(font
					(size 1 1)
					(thickness 0.15)
				)
			)
		)
		(property "MPN" "685119134923"
			(at 310.18 260.208 0)
			(layer "F.Fab")
			(hide yes)
			(effects
				(font
					(size 1 1)
					(thickness 0.15)
				)
			)
		)
		(property "Manufacturer" "Würth Elektronik"
			(at 310.18 260.208 0)
			(layer "F.Fab")
			(hide yes)
			(effects
				(font
					(size 1 1)
					(thickness 0.15)
				)
			)
		)
		(sheetname "Interfaces")
		(sheetfile "interfaces.kicad_sch")
		(attr smd)
		(fp_line
			(start 7.55 2.75)
			(end 7.55 -0.15)
			(stroke
				(width 0.12)
				(type solid)
			)
			(layer "F.SilkS")
		)
		(fp_line
			(start 5.7 5.65)
			(end 4.75 5.65)
			(stroke
				(width 0.12)
				(type solid)
			)
			(layer "F.SilkS")
		)
		(fp_line
			(start -4.85 5.65)
			(end -5.8 5.65)
			(stroke
				(width 0.12)
				(type solid)
			)
			(layer "F.SilkS")
		)
		(fp_line
			(start -7.55 -0.125)
			(end -7.55 2.65)
			(stroke
				(width 0.12)
				(type solid)
			)
			(layer "F.SilkS")
		)
		(fp_circle
			(center -4.9 5.9)
			(end -4.85 5.9)
			(stroke
				(width 0.15)
				(type solid)
			)
			(fill no)
			(layer "F.SilkS")
		)
		(fp_rect
			(start -8.05 -6.32)
			(end 7.949 6.78)
			(stroke
				(width 0.05)
				(type solid)
			)
			(fill no)
			(layer "F.CrtYd")
		)
		(fp_line
			(start 6.95 6.535)
			(end 6.95 -5.616)
			(stroke
				(width 0.15)
				(type solid)
			)
			(layer "F.Fab")
		)
		(fp_line
			(start 6.95 6.535)
			(end -6.05 6.535)
			(stroke
				(width 0.15)
				(type solid)
			)
			(layer "F.Fab")
		)
		(fp_line
			(start -7.05 5.525)
			(end -6.05 6.525)
			(stroke
				(width 0.15)
				(type solid)
			)
			(layer "F.Fab")
		)
		(fp_line
			(start -7.05 5.525)
			(end -7.05 -5.616)
			(stroke
				(width 0.15)
				(type solid)
			)
			(layer "F.Fab")
		)
		(fp_line
			(start -7.05 -5.616)
			(end 6.95 -5.616)
			(stroke
				(width 0.15)
				(type solid)
			)
			(layer "F.Fab")
		)
		(pad "1" smd rect
			(at -4.55 5.224 180)
			(size 0.28 2.6)
			(layers "F.Cu" "F.Mask" "F.Paste")
			(net 670 "/Interfaces/C_TMDS_D2_P")
			(pinfunction "D2+")
			(pintype "bidirectional")
		)
		(pad "2" smd rect
			(at -4.05 5.224 180)
			(size 0.28 2.6)
			(layers "F.Cu" "F.Mask" "F.Paste")
			(net 5 "GND")
			(pinfunction "D2S")
			(pintype "passive")
		)
		(pad "3" smd rect
			(at -3.551 5.224 180)
			(size 0.28 2.6)
			(layers "F.Cu" "F.Mask" "F.Paste")
			(net 669 "/Interfaces/C_TMDS_D2_N")
			(pinfunction "D2-")
			(pintype "bidirectional")
		)
		(pad "4" smd rect
			(at -3.051 5.224 180)
			(size 0.28 2.6)
			(layers "F.Cu" "F.Mask" "F.Paste")
			(net 668 "/Interfaces/C_TMDS_D1_P")
			(pinfunction "D1+")
			(pintype "bidirectional")
		)
		(pad "5" smd rect
			(at -2.551 5.224 180)
			(size 0.28 2.6)
			(layers "F.Cu" "F.Mask" "F.Paste")
			(net 5 "GND")
			(pinfunction "D1S")
			(pintype "passive")
		)
		(pad "6" smd rect
			(at -2.05 5.224 180)
			(size 0.28 2.6)
			(layers "F.Cu" "F.Mask" "F.Paste")
			(net 667 "/Interfaces/C_TMDS_D1_N")
			(pinfunction "D1-")
			(pintype "bidirectional")
		)
		(pad "7" smd rect
			(at -1.551 5.224 180)
			(size 0.28 2.6)
			(layers "F.Cu" "F.Mask" "F.Paste")
			(net 666 "/Interfaces/C_TMDS_D0_P")
			(pinfunction "D0+")
			(pintype "bidirectional")
		)
		(pad "8" smd rect
			(at -1.051 5.224 180)
			(size 0.28 2.6)
			(layers "F.Cu" "F.Mask" "F.Paste")
			(net 5 "GND")
			(pinfunction "D0S")
			(pintype "passive")
		)
		(pad "9" smd rect
			(at -0.551 5.224 180)
			(size 0.28 2.6)
			(layers "F.Cu" "F.Mask" "F.Paste")
			(net 665 "/Interfaces/C_TMDS_D0_N")
			(pinfunction "D0-")
			(pintype "bidirectional")
		)
		(pad "10" smd rect
			(at -0.051 5.224 180)
			(size 0.28 2.6)
			(layers "F.Cu" "F.Mask" "F.Paste")
			(net 664 "/Interfaces/C_TMDS_CLK_P")
			(pinfunction "CK+")
			(pintype "bidirectional")
		)
		(pad "11" smd rect
			(at 0.45 5.224 180)
			(size 0.28 2.6)
			(layers "F.Cu" "F.Mask" "F.Paste")
			(net 5 "GND")
			(pinfunction "CKS")
			(pintype "passive")
		)
		(pad "12" smd rect
			(at 0.95 5.224 180)
			(size 0.28 2.6)
			(layers "F.Cu" "F.Mask" "F.Paste")
			(net 663 "/Interfaces/C_TMDS_CLK_N")
			(pinfunction "CK-")
			(pintype "bidirectional")
		)
		(pad "13" smd rect
			(at 1.449 5.224 180)
			(size 0.28 2.6)
			(layers "F.Cu" "F.Mask" "F.Paste")
			(net 80 "Net-(J2-CEC)")
			(pinfunction "CEC")
			(pintype "bidirectional")
		)
		(pad "14" smd rect
			(at 1.949 5.224 180)
			(size 0.28 2.6)
			(layers "F.Cu" "F.Mask" "F.Paste")
			(net 79 "unconnected-(J2-UTILITY{slash}HEAC+-Pad14)")
			(pinfunction "UTILITY/HEAC+")
			(pintype "bidirectional+no_connect")
		)
		(pad "15" smd rect
			(at 2.45 5.224 180)
			(size 0.28 2.6)
			(layers "F.Cu" "F.Mask" "F.Paste")
			(net 81 "Net-(J2-SCL)")
			(pinfunction "SCL")
			(pintype "bidirectional")
		)
		(pad "16" smd rect
			(at 2.95 5.224 180)
			(size 0.28 2.6)
			(layers "F.Cu" "F.Mask" "F.Paste")
			(net 82 "Net-(J2-SDA)")
			(pinfunction "SDA")
			(pintype "bidirectional")
		)
		(pad "17" smd rect
			(at 3.45 5.224 180)
			(size 0.28 2.6)
			(layers "F.Cu" "F.Mask" "F.Paste")
			(net 5 "GND")
			(pinfunction "GND")
			(pintype "power_in")
		)
		(pad "18" smd rect
			(at 3.95 5.224 180)
			(size 0.28 2.6)
			(layers "F.Cu" "F.Mask" "F.Paste")
			(net 83 "Net-(J2-+5V)")
			(pinfunction "+5V")
			(pintype "power_in")
		)
		(pad "19" smd rect
			(at 4.45 5.224 180)
			(size 0.28 2.6)
			(layers "F.Cu" "F.Mask" "F.Paste")
			(net 84 "Net-(J2-HPD{slash}HEAC-)")
			(pinfunction "HPD/HEAC-")
			(pintype "bidirectional")
		)
		(pad "SH" thru_hole oval
			(at -7.3 -1.577 180)
			(size 1.5 2.7)
			(drill oval 0.9 2.1)
			(layers "*.Cu" "*.Mask")
			(remove_unused_layers no)
			(net 5 "GND")
			(pinfunction "SH")
			(pintype "passive")
		)
		(pad "SH" thru_hole oval
			(at -7.3 4.424 180)
			(size 1.5 3.3)
			(drill oval 0.9 2.7)
			(layers "*.Cu" "*.Mask")
			(remove_unused_layers no)
			(net 5 "GND")
			(pinfunction "SH")
			(pintype "passive")
		)
		(pad "SH" thru_hole oval
			(at 7.2 -1.577 180)
			(size 1.5 2.7)
			(drill oval 0.9 2.1)
			(layers "*.Cu" "*.Mask")
			(remove_unused_layers no)
			(net 5 "GND")
			(pinfunction "SH")
			(pintype "passive")
		)
		(pad "SH" thru_hole oval
			(at 7.2 4.424 180)
			(size 1.5 3.3)
			(drill oval 0.9 2.7)
			(layers "*.Cu" "*.Mask")
			(remove_unused_layers no)
			(net 5 "GND")
			(pinfunction "SH")
			(pintype "passive")
		)
	)
	(footprint "antmicro-footprints:C_0402_1005Metric"
		(layer "F.Cu")
		(at 138.286328 113.968157)
		(descr "Capacitor SMD 0402")
		(tags "capacitor SMD 0402")
		(property "Reference" "C11"
			(at -1.086328 -0.468157 0)
			(layer "F.SilkS")
			(effects
				(font
					(size 0.7 0.7)
					(thickness 0.15)
				)
				(justify left bottom)
			)
		)
		(property "Value" "C_100n_6V3_0402"
			(at 0 1.4 0)
			(layer "F.Fab")
			(effects
				(font
					(size 0.7 0.7)
					(thickness 0.15)
				)
				(justify left bottom)
			)
		)
		(property "Description" " "
			(at 0 0 0)
			(layer "F.Fab")
			(hide yes)
			(effects
				(font
					(size 1.27 1.27)
					(thickness 0.15)
				)
			)
		)
		(property "Author" "Antmicro"
			(at 0 0 0)
			(layer "F.Fab")
			(hide yes)
			(effects
				(font
					(size 1 1)
					(thickness 0.15)
				)
			)
		)
		(property "Dielectric" ""
			(at 0 0 0)
			(layer "F.Fab")
			(hide yes)
			(effects
				(font
					(size 1 1)
					(thickness 0.15)
				)
			)
		)
		(property "License" "Apache-2.0"
			(at 0 0 0)
			(layer "F.Fab")
			(hide yes)
			(effects
				(font
					(size 1 1)
					(thickness 0.15)
				)
			)
		)
		(property "MPN" "0402X104K6R3CT"
			(at 0 0 0)
			(layer "F.Fab")
			(hide yes)
			(effects
				(font
					(size 1 1)
					(thickness 0.15)
				)
			)
		)
		(property "Manufacturer" "Walsin"
			(at 0 0 0)
			(layer "F.Fab")
			(hide yes)
			(effects
				(font
					(size 1 1)
					(thickness 0.15)
				)
			)
		)
		(property "Val" "100n"
			(at 0 0 0)
			(layer "F.Fab")
			(hide yes)
			(effects
				(font
					(size 1 1)
					(thickness 0.15)
				)
			)
		)
		(property "Voltage" ""
			(at 0 0 0)
			(layer "F.Fab")
			(hide yes)
			(effects
				(font
					(size 1 1)
					(thickness 0.15)
				)
			)
		)
		(sheetname "Interfaces")
		(sheetfile "interfaces.kicad_sch")
		(attr smd)
		(fp_rect
			(start -0.94 -0.47)
			(end 0.94 0.47)
			(stroke
				(width 0.05)
				(type solid)
			)
			(fill no)
			(layer "F.CrtYd")
		)
		(fp_rect
			(start -0.499 -0.249)
			(end 0.499 0.249)
			(stroke
				(width 0.15)
				(type solid)
			)
			(fill no)
			(layer "F.Fab")
		)
		(pad "1" smd roundrect
			(at -0.484 0)
			(size 0.59 0.64)
			(layers "F.Cu" "F.Mask" "F.Paste")
			(roundrect_rratio 0.25)
			(net 5 "GND")
			(pintype "passive")
		)
		(pad "2" smd roundrect
			(at 0.484 0)
			(size 0.59 0.64)
			(layers "F.Cu" "F.Mask" "F.Paste")
			(roundrect_rratio 0.25)
			(net 653 "/Interfaces/VPHY")
			(pintype "passive")
		)
	)
	(footprint "antmicro-footprints:C_0402_1005Metric"
		(layer "F.Cu")
		(at 135.1 104.799 180)
		(descr "Capacitor SMD 0402")
		(tags "capacitor SMD 0402")
		(property "Reference" "C12"
			(at 2.9 -0.401 180)
			(layer "F.SilkS")
			(effects
				(font
					(size 0.7 0.7)
					(thickness 0.15)
				)
				(justify left bottom)
			)
		)
		(property "Value" "C_100n_6V3_0402"
			(at 0 1.4 180)
			(layer "F.Fab")
			(effects
				(font
					(size 0.7 0.7)
					(thickness 0.15)
				)
				(justify left bottom)
			)
		)
		(property "Description" " "
			(at 0 0 180)
			(layer "F.Fab")
			(hide yes)
			(effects
				(font
					(size 1.27 1.27)
					(thickness 0.15)
				)
			)
		)
		(property "Author" "Antmicro"
			(at 270.2 209.598 0)
			(layer "F.Fab")
			(hide yes)
			(effects
				(font
					(size 1 1)
					(thickness 0.15)
				)
			)
		)
		(property "Dielectric" ""
			(at 270.2 209.598 0)
			(layer "F.Fab")
			(hide yes)
			(effects
				(font
					(size 1 1)
					(thickness 0.15)
				)
			)
		)
		(property "License" "Apache-2.0"
			(at 270.2 209.598 0)
			(layer "F.Fab")
			(hide yes)
			(effects
				(font
					(size 1 1)
					(thickness 0.15)
				)
			)
		)
		(property "MPN" "0402X104K6R3CT"
			(at 270.2 209.598 0)
			(layer "F.Fab")
			(hide yes)
			(effects
				(font
					(size 1 1)
					(thickness 0.15)
				)
			)
		)
		(property "Manufacturer" "Walsin"
			(at 270.2 209.598 0)
			(layer "F.Fab")
			(hide yes)
			(effects
				(font
					(size 1 1)
					(thickness 0.15)
				)
			)
		)
		(property "Val" "100n"
			(at 270.2 209.598 0)
			(layer "F.Fab")
			(hide yes)
			(effects
				(font
					(size 1 1)
					(thickness 0.15)
				)
			)
		)
		(property "Voltage" ""
			(at 270.2 209.598 0)
			(layer "F.Fab")
			(hide yes)
			(effects
				(font
					(size 1 1)
					(thickness 0.15)
				)
			)
		)
		(sheetname "Interfaces")
		(sheetfile "interfaces.kicad_sch")
		(attr smd)
		(fp_rect
			(start -0.94 -0.47)
			(end 0.94 0.47)
			(stroke
				(width 0.05)
				(type solid)
			)
			(fill no)
			(layer "F.CrtYd")
		)
		(fp_rect
			(start -0.499 -0.249)
			(end 0.499 0.249)
			(stroke
				(width 0.15)
				(type solid)
			)
			(fill no)
			(layer "F.Fab")
		)
		(pad "1" smd roundrect
			(at -0.484 0 180)
			(size 0.59 0.64)
			(layers "F.Cu" "F.Mask" "F.Paste")
			(roundrect_rratio 0.25)
			(net 459 "3V3_SYS")
			(pintype "passive")
		)
		(pad "2" smd roundrect
			(at 0.484 0 180)
			(size 0.59 0.64)
			(layers "F.Cu" "F.Mask" "F.Paste")
			(roundrect_rratio 0.25)
			(net 5 "GND")
			(pintype "passive")
		)
	)
	(footprint "antmicro-footprints:C_0402_1005Metric"
		(layer "F.Cu")
		(at 135.1 103.751157)
		(descr "Capacitor SMD 0402")
		(tags "capacitor SMD 0402")
		(property "Reference" "C17"
			(at -2.9 0.348843 0)
			(layer "F.SilkS")
			(effects
				(font
					(size 0.7 0.7)
					(thickness 0.15)
				)
				(justify left bottom)
			)
		)
		(property "Value" "C_100n_6V3_0402"
			(at 0 1.4 0)
			(layer "F.Fab")
			(effects
				(font
					(size 0.7 0.7)
					(thickness 0.15)
				)
				(justify left bottom)
			)
		)
		(property "Description" " "
			(at 0 0 0)
			(layer "F.Fab")
			(hide yes)
			(effects
				(font
					(size 1.27 1.27)
					(thickness 0.15)
				)
			)
		)
		(property "Author" "Antmicro"
			(at 0 0 0)
			(layer "F.Fab")
			(hide yes)
			(effects
				(font
					(size 1 1)
					(thickness 0.15)
				)
			)
		)
		(property "Dielectric" ""
			(at 0 0 0)
			(layer "F.Fab")
			(hide yes)
			(effects
				(font
					(size 1 1)
					(thickness 0.15)
				)
			)
		)
		(property "License" "Apache-2.0"
			(at 0 0 0)
			(layer "F.Fab")
			(hide yes)
			(effects
				(font
					(size 1 1)
					(thickness 0.15)
				)
			)
		)
		(property "MPN" "0402X104K6R3CT"
			(at 0 0 0)
			(layer "F.Fab")
			(hide yes)
			(effects
				(font
					(size 1 1)
					(thickness 0.15)
				)
			)
		)
		(property "Manufacturer" "Walsin"
			(at 0 0 0)
			(layer "F.Fab")
			(hide yes)
			(effects
				(font
					(size 1 1)
					(thickness 0.15)
				)
			)
		)
		(property "Val" "100n"
			(at 0 0 0)
			(layer "F.Fab")
			(hide yes)
			(effects
				(font
					(size 1 1)
					(thickness 0.15)
				)
			)
		)
		(property "Voltage" ""
			(at 0 0 0)
			(layer "F.Fab")
			(hide yes)
			(effects
				(font
					(size 1 1)
					(thickness 0.15)
				)
			)
		)
		(sheetname "Interfaces")
		(sheetfile "interfaces.kicad_sch")
		(attr smd)
		(fp_rect
			(start -0.94 -0.47)
			(end 0.94 0.47)
			(stroke
				(width 0.05)
				(type solid)
			)
			(fill no)
			(layer "F.CrtYd")
		)
		(fp_rect
			(start -0.499 -0.249)
			(end 0.499 0.249)
			(stroke
				(width 0.15)
				(type solid)
			)
			(fill no)
			(layer "F.Fab")
		)
		(pad "1" smd roundrect
			(at -0.484 0)
			(size 0.59 0.64)
			(layers "F.Cu" "F.Mask" "F.Paste")
			(roundrect_rratio 0.25)
			(net 5 "GND")
			(pintype "passive")
		)
		(pad "2" smd roundrect
			(at 0.484 0)
			(size 0.59 0.64)
			(layers "F.Cu" "F.Mask" "F.Paste")
			(roundrect_rratio 0.25)
			(net 2 "/Interfaces/1V8_FT")
			(pintype "passive")
		)
	)
)
